(kicad_pcb
	(version 20241229)
	(generator "pcbnew")
	(generator_version "9.0")
	(general
		(thickness 1.599998)
		(legacy_teardrops no)
	)
	(paper "A4")
	(title_block
		(date "2023-02-12")
		(rev "1.1.5")
		(comment 9 "footprints 114-119 of 473")
	)
	(layers
		(0 "F.Cu" signal)
		(4 "In1.Cu" power "In1.GND")
		(6 "In2.Cu" signal)
		(8 "In3.Cu" power "In3.GND")
		(10 "In4.Cu" power "In4.VCC")
		(12 "In5.Cu" signal)
		(14 "In6.Cu" power "In6.VCC")
		(2 "B.Cu" signal)
		(9 "F.Adhes" user "F.Adhesive")
		(11 "B.Adhes" user "B.Adhesive")
		(13 "F.Paste" user)
		(15 "B.Paste" user)
		(5 "F.SilkS" user "F.Silkscreen")
		(7 "B.SilkS" user "B.Silkscreen")
		(1 "F.Mask" user)
		(3 "B.Mask" user)
		(17 "Dwgs.User" user "User.Drawings")
		(19 "Cmts.User" user "User.Comments")
		(21 "Eco1.User" user "User.Eco1")
		(23 "Eco2.User" user "User.Eco2")
		(25 "Edge.Cuts" user)
		(27 "Margin" user)
		(31 "F.CrtYd" user "F.Courtyard")
		(29 "B.CrtYd" user "B.Courtyard")
		(35 "F.Fab" user)
		(33 "B.Fab" user)
	)
	(footprint "antmicro-footprints:antmicro-logo"
		(layer "F.Cu")
		(at 198.886328 51.020008)
		(property "Reference" "N1"
			(at 0.05 -5.5 0)
			(layer "F.SilkS")
			(hide yes)
			(effects
				(font
					(size 0.7 0.7)
					(thickness 0.15)
				)
				(justify left bottom)
			)
		)
		(property "Value" "antmicro_logo"
			(at -0.101 5.099 0)
			(layer "F.SilkS")
			(hide yes)
			(effects
				(font
					(size 0.7 0.7)
					(thickness 0.15)
				)
				(justify left bottom)
			)
		)
		(property "Author" "Antmicro"
			(at 0 0 0)
			(layer "F.Fab")
			(hide yes)
			(effects
				(font
					(size 1 1)
					(thickness 0.15)
				)
			)
		)
		(property "License" "Apache-2.0"
			(at 0 0 0)
			(layer "F.Fab")
			(hide yes)
			(effects
				(font
					(size 1 1)
					(thickness 0.15)
				)
			)
		)
		(property "MPN" ""
			(at 0 0 0)
			(layer "F.Fab")
			(hide yes)
			(effects
				(font
					(size 1 1)
					(thickness 0.15)
				)
			)
		)
		(property "Manufacturer" ""
			(at 0 0 0)
			(layer "F.Fab")
			(hide yes)
			(effects
				(font
					(size 1 1)
					(thickness 0.15)
				)
			)
		)
		(sheetfile "lpddr4-test-board.kicad_sch")
	)
	(footprint "antmicro-footprints:RJ45_7499111121A_Horizontal"
		(layer "F.Cu")
		(at 195.721328 116.057157)
		(descr "WE-RJ45_Transformer-10/100/1000")
		(property "Reference" "J5"
			(at 4.978672 -2.457157 180)
			(layer "F.SilkS")
			(effects
				(font
					(size 0.7 0.7)
					(thickness 0.15)
				)
				(justify left bottom)
			)
		)
		(property "Value" "Bus_RJ45_7499111121A"
			(at 0 21.9 180)
			(layer "F.Fab")
			(effects
				(font
					(size 0.7 0.7)
					(thickness 0.15)
				)
				(justify left bottom)
			)
		)
		(property "Author" "Antmicro"
			(at 0 0 0)
			(layer "F.Fab")
			(hide yes)
			(effects
				(font
					(size 1 1)
					(thickness 0.15)
				)
			)
		)
		(property "License" "Apache-2.0"
			(at 0 0 0)
			(layer "F.Fab")
			(hide yes)
			(effects
				(font
					(size 1 1)
					(thickness 0.15)
				)
			)
		)
		(property "MPN" "7499111121A"
			(at 0 0 0)
			(layer "F.Fab")
			(hide yes)
			(effects
				(font
					(size 1 1)
					(thickness 0.15)
				)
			)
		)
		(property "Manufacturer" "Würth Elektronik"
			(at 0 0 0)
			(layer "F.Fab")
			(hide yes)
			(effects
				(font
					(size 1 1)
					(thickness 0.15)
				)
			)
		)
		(sheetname "Ethernet")
		(sheetfile "ethernet.kicad_sch")
		(attr through_hole)
		(fp_line
			(start -2.323 4.292)
			(end -2.323 -2.16)
			(stroke
				(width 0.15)
				(type solid)
			)
			(layer "F.SilkS")
		)
		(fp_line
			(start -2.323 19.7)
			(end -2.323 7.391)
			(stroke
				(width 0.15)
				(type solid)
			)
			(layer "F.SilkS")
		)
		(fp_line
			(start -2.323 19.7)
			(end 13.756 19.7)
			(stroke
				(width 0.15)
				(type solid)
			)
			(layer "F.SilkS")
		)
		(fp_line
			(start 13.756 -2.16)
			(end -2.323 -2.16)
			(stroke
				(width 0.15)
				(type solid)
			)
			(layer "F.SilkS")
		)
		(fp_line
			(start 13.756 4.292)
			(end 13.756 -2.16)
			(stroke
				(width 0.15)
				(type solid)
			)
			(layer "F.SilkS")
		)
		(fp_line
			(start 13.756 7.391)
			(end 13.756 19.7)
			(stroke
				(width 0.15)
				(type solid)
			)
			(layer "F.SilkS")
		)
		(fp_rect
			(start 14.838 20.181)
			(end -3.406 -3.059)
			(stroke
				(width 0.05)
				(type solid)
			)
			(fill no)
			(layer "F.CrtYd")
		)
		(fp_line
			(start -2.225 -2.059)
			(end -2.225 19.781)
			(stroke
				(width 0.15)
				(type solid)
			)
			(layer "F.Fab")
		)
		(fp_line
			(start -2.225 19.781)
			(end 13.657 19.781)
			(stroke
				(width 0.15)
				(type solid)
			)
			(layer "F.Fab")
		)
		(fp_line
			(start 13.657 -2.059)
			(end -2.225 -2.059)
			(stroke
				(width 0.15)
				(type solid)
			)
			(layer "F.Fab")
		)
		(fp_line
			(start 13.657 19.781)
			(end 13.657 -2.059)
			(stroke
				(width 0.15)
				(type solid)
			)
			(layer "F.Fab")
		)
		(pad "" np_thru_hole circle
			(at 0 8.891 180)
			(size 3.25 3.25)
			(drill 3.25)
			(layers "*.Cu" "*.Mask")
		)
		(pad "" np_thru_hole circle
			(at 11.43 8.891 180)
			(size 3.25 3.25)
			(drill 3.25)
			(layers "*.Cu" "*.Mask")
		)
		(pad "1" thru_hole circle
			(at 0 0 180)
			(size 1.408 1.408)
			(drill 0.9)
			(layers "*.Cu" "*.Mask")
			(remove_unused_layers no)
			(net 522 "/Ethernet/ETH1_P")
			(pinfunction "D1+")
			(pintype "bidirectional")
		)
		(pad "2" thru_hole circle
			(at 1.27 2.541 180)
			(size 1.408 1.408)
			(drill 0.9)
			(layers "*.Cu" "*.Mask")
			(remove_unused_layers no)
			(net 525 "/Ethernet/ETH1_N")
			(pinfunction "D1-")
			(pintype "bidirectional")
		)
		(pad "3" thru_hole circle
			(at 2.54 0 180)
			(size 1.408 1.408)
			(drill 0.9)
			(layers "*.Cu" "*.Mask")
			(remove_unused_layers no)
			(net 520 "/Ethernet/ETH2_P")
			(pinfunction "D2+")
			(pintype "bidirectional")
		)
		(pad "4" thru_hole circle
			(at 3.81 2.541 180)
			(size 1.408 1.408)
			(drill 0.9)
			(layers "*.Cu" "*.Mask")
			(remove_unused_layers no)
			(net 519 "/Ethernet/ETH3_P")
			(pinfunction "D3+")
			(pintype "bidirectional")
		)
		(pad "5" thru_hole circle
			(at 5.08 0 180)
			(size 1.408 1.408)
			(drill 0.9)
			(layers "*.Cu" "*.Mask")
			(remove_unused_layers no)
			(net 526 "/Ethernet/ETH3_N")
			(pinfunction "D3-")
			(pintype "bidirectional")
		)
		(pad "6" thru_hole circle
			(at 6.351 2.541 180)
			(size 1.408 1.408)
			(drill 0.9)
			(layers "*.Cu" "*.Mask")
			(remove_unused_layers no)
			(net 524 "/Ethernet/ETH2_N")
			(pinfunction "D2-")
			(pintype "bidirectional")
		)
		(pad "7" thru_hole circle
			(at 7.62 0 180)
			(size 1.408 1.408)
			(drill 0.9)
			(layers "*.Cu" "*.Mask")
			(remove_unused_layers no)
			(net 523 "/Ethernet/ETH4_P")
			(pinfunction "D4+")
			(pintype "bidirectional")
		)
		(pad "8" thru_hole circle
			(at 8.891 2.541 180)
			(size 1.408 1.408)
			(drill 0.9)
			(layers "*.Cu" "*.Mask")
			(remove_unused_layers no)
			(net 527 "/Ethernet/ETH4_N")
			(pinfunction "D4-")
			(pintype "bidirectional")
		)
		(pad "9" thru_hole circle
			(at 10.16 0 180)
			(size 1.408 1.408)
			(drill 0.9)
			(layers "*.Cu" "*.Mask")
			(remove_unused_layers no)
			(net 88 "unconnected-(J5-VCC-Pad9)")
			(pinfunction "VCC")
			(pintype "power_in+no_connect")
		)
		(pad "10" thru_hole circle
			(at 11.43 2.541 180)
			(size 1.408 1.408)
			(drill 0.9)
			(layers "*.Cu" "*.Mask")
			(remove_unused_layers no)
			(net 5 "GND")
			(pinfunction "GND")
			(pintype "power_in")
		)
		(pad "11" thru_hole circle
			(at -0.915 12.971 180)
			(size 1.53 1.53)
			(drill 1.02)
			(layers "*.Cu" "*.Mask")
			(remove_unused_layers no)
			(net 89 "Net-(J5-LED1_Y+)")
			(pinfunction "LED1_Y+")
			(pintype "passive")
		)
		(pad "12" thru_hole circle
			(at 1.625 12.971 180)
			(size 1.53 1.53)
			(drill 1.02)
			(layers "*.Cu" "*.Mask")
			(remove_unused_layers no)
			(net 12 "LED_LINK")
			(pinfunction "LED1_Y-")
			(pintype "passive")
		)
		(pad "13" thru_hole circle
			(at 9.805 12.971 180)
			(size 1.53 1.53)
			(drill 1.02)
			(layers "*.Cu" "*.Mask")
			(remove_unused_layers no)
			(net 90 "Net-(J5-LED2_G+)")
			(pinfunction "LED2_G+")
			(pintype "passive")
		)
		(pad "14" thru_hole circle
			(at 12.346 12.971 180)
			(size 1.53 1.53)
			(drill 1.02)
			(layers "*.Cu" "*.Mask")
			(remove_unused_layers no)
			(net 13 "LED_SPD")
			(pinfunction "LED2_G-")
			(pintype "passive")
		)
		(pad "SH" thru_hole circle
			(at -2.03 5.842 180)
			(size 2.4 2.4)
			(drill 1.6)
			(layers "*.Cu" "*.Mask")
			(remove_unused_layers no)
			(net 521 "Net-(FB7-Pad1)")
			(pintype "passive")
		)
		(pad "SH" thru_hole circle
			(at 13.462 5.842 180)
			(size 2.4 2.4)
			(drill 1.6)
			(layers "*.Cu" "*.Mask")
			(remove_unused_layers no)
			(net 521 "Net-(FB7-Pad1)")
			(pintype "passive")
		)
	)
	(footprint "antmicro-footprints:C_0402_1005Metric"
		(layer "F.Cu")
		(at 193.086328 98.874306 180)
		(descr "Capacitor SMD 0402")
		(tags "capacitor SMD 0402")
		(property "Reference" "C97"
			(at 1.172656 4.347612 180)
			(layer "F.SilkS")
			(effects
				(font
					(size 0.7 0.7)
					(thickness 0.15)
				)
				(justify left bottom)
			)
		)
		(property "Value" "C_4u7_0402"
			(at 0 1.4 180)
			(layer "F.Fab")
			(effects
				(font
					(size 0.7 0.7)
					(thickness 0.15)
				)
				(justify left bottom)
			)
		)
		(property "Description" " "
			(at 0 0 180)
			(layer "F.Fab")
			(hide yes)
			(effects
				(font
					(size 1.27 1.27)
					(thickness 0.15)
				)
			)
		)
		(property "Author" "Antmicro"
			(at 386.172656 197.748612 0)
			(layer "F.Fab")
			(hide yes)
			(effects
				(font
					(size 1 1)
					(thickness 0.15)
				)
			)
		)
		(property "Dielectric" ""
			(at 386.172656 197.748612 0)
			(layer "F.Fab")
			(hide yes)
			(effects
				(font
					(size 1 1)
					(thickness 0.15)
				)
			)
		)
		(property "License" "Apache-2.0"
			(at 386.172656 197.748612 0)
			(layer "F.Fab")
			(hide yes)
			(effects
				(font
					(size 1 1)
					(thickness 0.15)
				)
			)
		)
		(property "MPN" "GRM155R61A475MEAAD"
			(at 386.172656 197.748612 0)
			(layer "F.Fab")
			(hide yes)
			(effects
				(font
					(size 1 1)
					(thickness 0.15)
				)
			)
		)
		(property "Manufacturer" "Murata"
			(at 386.172656 197.748612 0)
			(layer "F.Fab")
			(hide yes)
			(effects
				(font
					(size 1 1)
					(thickness 0.15)
				)
			)
		)
		(property "Val" "4u7"
			(at 386.172656 197.748612 0)
			(layer "F.Fab")
			(hide yes)
			(effects
				(font
					(size 1 1)
					(thickness 0.15)
				)
			)
		)
		(property "Voltage" ""
			(at 386.172656 197.748612 0)
			(layer "F.Fab")
			(hide yes)
			(effects
				(font
					(size 1 1)
					(thickness 0.15)
				)
			)
		)
		(sheetname "Ethernet")
		(sheetfile "ethernet.kicad_sch")
		(attr smd)
		(fp_rect
			(start -0.94 -0.47)
			(end 0.94 0.47)
			(stroke
				(width 0.05)
				(type solid)
			)
			(fill no)
			(layer "F.CrtYd")
		)
		(fp_rect
			(start -0.499 -0.249)
			(end 0.499 0.249)
			(stroke
				(width 0.15)
				(type solid)
			)
			(fill no)
			(layer "F.Fab")
		)
		(pad "1" smd roundrect
			(at -0.484 0 180)
			(size 0.59 0.64)
			(layers "F.Cu" "F.Mask" "F.Paste")
			(roundrect_rratio 0.25)
			(net 602 "1V2_SYS")
			(pintype "passive")
		)
		(pad "2" smd roundrect
			(at 0.484 0 180)
			(size 0.59 0.64)
			(layers "F.Cu" "F.Mask" "F.Paste")
			(roundrect_rratio 0.25)
			(net 5 "GND")
			(pintype "passive")
		)
	)
	(footprint "antmicro-footprints:C_0402_1005Metric"
		(layer "F.Cu")
		(at 193.086328 99.874306 180)
		(descr "Capacitor SMD 0402")
		(tags "capacitor SMD 0402")
		(property "Reference" "C98"
			(at 1.172656 4.347612 180)
			(layer "F.SilkS")
			(effects
				(font
					(size 0.7 0.7)
					(thickness 0.15)
				)
				(justify left bottom)
			)
		)
		(property "Value" "C_470n_0402"
			(at 0 1.4 180)
			(layer "F.Fab")
			(effects
				(font
					(size 0.7 0.7)
					(thickness 0.15)
				)
				(justify left bottom)
			)
		)
		(property "Description" " "
			(at 0 0 180)
			(layer "F.Fab")
			(hide yes)
			(effects
				(font
					(size 1.27 1.27)
					(thickness 0.15)
				)
			)
		)
		(property "Author" "Antmicro"
			(at 386.172656 199.748612 0)
			(layer "F.Fab")
			(hide yes)
			(effects
				(font
					(size 1 1)
					(thickness 0.15)
				)
			)
		)
		(property "Dielectric" ""
			(at 386.172656 199.748612 0)
			(layer "F.Fab")
			(hide yes)
			(effects
				(font
					(size 1 1)
					(thickness 0.15)
				)
			)
		)
		(property "License" "Apache-2.0"
			(at 386.172656 199.748612 0)
			(layer "F.Fab")
			(hide yes)
			(effects
				(font
					(size 1 1)
					(thickness 0.15)
				)
			)
		)
		(property "MPN" "C1005X5R1E474M050BB"
			(at 386.172656 199.748612 0)
			(layer "F.Fab")
			(hide yes)
			(effects
				(font
					(size 1 1)
					(thickness 0.15)
				)
			)
		)
		(property "Manufacturer" "TDK"
			(at 386.172656 199.748612 0)
			(layer "F.Fab")
			(hide yes)
			(effects
				(font
					(size 1 1)
					(thickness 0.15)
				)
			)
		)
		(property "Val" "470n"
			(at 386.172656 199.748612 0)
			(layer "F.Fab")
			(hide yes)
			(effects
				(font
					(size 1 1)
					(thickness 0.15)
				)
			)
		)
		(property "Voltage" ""
			(at 386.172656 199.748612 0)
			(layer "F.Fab")
			(hide yes)
			(effects
				(font
					(size 1 1)
					(thickness 0.15)
				)
			)
		)
		(sheetname "Ethernet")
		(sheetfile "ethernet.kicad_sch")
		(attr smd)
		(fp_rect
			(start -0.94 -0.47)
			(end 0.94 0.47)
			(stroke
				(width 0.05)
				(type solid)
			)
			(fill no)
			(layer "F.CrtYd")
		)
		(fp_rect
			(start -0.499 -0.249)
			(end 0.499 0.249)
			(stroke
				(width 0.15)
				(type solid)
			)
			(fill no)
			(layer "F.Fab")
		)
		(pad "1" smd roundrect
			(at -0.484 0 180)
			(size 0.59 0.64)
			(layers "F.Cu" "F.Mask" "F.Paste")
			(roundrect_rratio 0.25)
			(net 602 "1V2_SYS")
			(pintype "passive")
		)
		(pad "2" smd roundrect
			(at 0.484 0 180)
			(size 0.59 0.64)
			(layers "F.Cu" "F.Mask" "F.Paste")
			(roundrect_rratio 0.25)
			(net 5 "GND")
			(pintype "passive")
		)
	)
	(footprint "antmicro-footprints:C_0402_1005Metric"
		(layer "F.Cu")
		(at 193.586328 101.374306 90)
		(descr "Capacitor SMD 0402")
		(tags "capacitor SMD 0402")
		(property "Reference" "C102"
			(at 2.974306 0.413672 90)
			(layer "F.SilkS")
			(effects
				(font
					(size 0.7 0.7)
					(thickness 0.15)
				)
				(justify left bottom)
			)
		)
		(property "Value" "C_4u7_0402"
			(at 0 1.4 90)
			(layer "F.Fab")
			(effects
				(font
					(size 0.7 0.7)
					(thickness 0.15)
				)
				(justify left bottom)
			)
		)
		(property "Description" " "
			(at 0 0 90)
			(layer "F.Fab")
			(hide yes)
			(effects
				(font
					(size 1.27 1.27)
					(thickness 0.15)
				)
			)
		)
		(property "Author" "Antmicro"
			(at 294.960634 -92.212022 0)
			(layer "F.Fab")
			(hide yes)
			(effects
				(font
					(size 1 1)
					(thickness 0.15)
				)
			)
		)
		(property "Dielectric" ""
			(at 294.960634 -92.212022 0)
			(layer "F.Fab")
			(hide yes)
			(effects
				(font
					(size 1 1)
					(thickness 0.15)
				)
			)
		)
		(property "License" "Apache-2.0"
			(at 294.960634 -92.212022 0)
			(layer "F.Fab")
			(hide yes)
			(effects
				(font
					(size 1 1)
					(thickness 0.15)
				)
			)
		)
		(property "MPN" "GRM155R61A475MEAAD"
			(at 294.960634 -92.212022 0)
			(layer "F.Fab")
			(hide yes)
			(effects
				(font
					(size 1 1)
					(thickness 0.15)
				)
			)
		)
		(property "Manufacturer" "Murata"
			(at 294.960634 -92.212022 0)
			(layer "F.Fab")
			(hide yes)
			(effects
				(font
					(size 1 1)
					(thickness 0.15)
				)
			)
		)
		(property "Val" "4u7"
			(at 294.960634 -92.212022 0)
			(layer "F.Fab")
			(hide yes)
			(effects
				(font
					(size 1 1)
					(thickness 0.15)
				)
			)
		)
		(property "Voltage" ""
			(at 294.960634 -92.212022 0)
			(layer "F.Fab")
			(hide yes)
			(effects
				(font
					(size 1 1)
					(thickness 0.15)
				)
			)
		)
		(sheetname "Ethernet")
		(sheetfile "ethernet.kicad_sch")
		(attr smd)
		(fp_rect
			(start -0.94 -0.47)
			(end 0.94 0.47)
			(stroke
				(width 0.05)
				(type solid)
			)
			(fill no)
			(layer "F.CrtYd")
		)
		(fp_rect
			(start -0.499 -0.249)
			(end 0.499 0.249)
			(stroke
				(width 0.15)
				(type solid)
			)
			(fill no)
			(layer "F.Fab")
		)
		(pad "1" smd roundrect
			(at -0.484 0 90)
			(size 0.59 0.64)
			(layers "F.Cu" "F.Mask" "F.Paste")
			(roundrect_rratio 0.25)
			(net 530 "/Ethernet/AVDDL_PLL")
			(pintype "passive")
		)
		(pad "2" smd roundrect
			(at 0.484 0 90)
			(size 0.59 0.64)
			(layers "F.Cu" "F.Mask" "F.Paste")
			(roundrect_rratio 0.25)
			(net 5 "GND")
			(pintype "passive")
		)
	)
	(footprint "antmicro-footprints:C_0402_1005Metric"
		(layer "F.Cu")
		(at 192.486328 101.374306 90)
		(descr "Capacitor SMD 0402")
		(tags "capacitor SMD 0402")
		(property "Reference" "C106"
			(at 2.974306 0.413672 90)
			(layer "F.SilkS")
			(effects
				(font
					(size 0.7 0.7)
					(thickness 0.15)
				)
				(justify left bottom)
			)
		)
		(property "Value" "C_100n_16V_0402"
			(at 0 1.4 90)
			(layer "F.Fab")
			(effects
				(font
					(size 0.7 0.7)
					(thickness 0.15)
				)
				(justify left bottom)
			)
		)
		(property "Description" " "
			(at 0 0 90)
			(layer "F.Fab")
			(hide yes)
			(effects
				(font
					(size 1.27 1.27)
					(thickness 0.15)
				)
			)
		)
		(property "Author" "Antmicro"
			(at 293.860634 -91.112022 0)
			(layer "F.Fab")
			(hide yes)
			(effects
				(font
					(size 1 1)
					(thickness 0.15)
				)
			)
		)
		(property "Dielectric" ""
			(at 293.860634 -91.112022 0)
			(layer "F.Fab")
			(hide yes)
			(effects
				(font
					(size 1 1)
					(thickness 0.15)
				)
			)
		)
		(property "License" "Apache-2.0"
			(at 293.860634 -91.112022 0)
			(layer "F.Fab")
			(hide yes)
			(effects
				(font
					(size 1 1)
					(thickness 0.15)
				)
			)
		)
		(property "MPN" "MC0402B104K160CT"
			(at 293.860634 -91.112022 0)
			(layer "F.Fab")
			(hide yes)
			(effects
				(font
					(size 1 1)
					(thickness 0.15)
				)
			)
		)
		(property "Manufacturer" "Multicomp"
			(at 293.860634 -91.112022 0)
			(layer "F.Fab")
			(hide yes)
			(effects
				(font
					(size 1 1)
					(thickness 0.15)
				)
			)
		)
		(property "Val" "100n"
			(at 293.860634 -91.112022 0)
			(layer "F.Fab")
			(hide yes)
			(effects
				(font
					(size 1 1)
					(thickness 0.15)
				)
			)
		)
		(property "Voltage" ""
			(at 293.860634 -91.112022 0)
			(layer "F.Fab")
			(hide yes)
			(effects
				(font
					(size 1 1)
					(thickness 0.15)
				)
			)
		)
		(sheetname "Ethernet")
		(sheetfile "ethernet.kicad_sch")
		(attr smd)
		(fp_rect
			(start -0.94 -0.47)
			(end 0.94 0.47)
			(stroke
				(width 0.05)
				(type solid)
			)
			(fill no)
			(layer "F.CrtYd")
		)
		(fp_rect
			(start -0.499 -0.249)
			(end 0.499 0.249)
			(stroke
				(width 0.15)
				(type solid)
			)
			(fill no)
			(layer "F.Fab")
		)
		(pad "1" smd roundrect
			(at -0.484 0 90)
			(size 0.59 0.64)
			(layers "F.Cu" "F.Mask" "F.Paste")
			(roundrect_rratio 0.25)
			(net 530 "/Ethernet/AVDDL_PLL")
			(pintype "passive")
		)
		(pad "2" smd roundrect
			(at 0.484 0 90)
			(size 0.59 0.64)
			(layers "F.Cu" "F.Mask" "F.Paste")
			(roundrect_rratio 0.25)
			(net 5 "GND")
			(pintype "passive")
		)
	)
)
